# SCM (Grand Teton) — schematic netlist excerpt (pin names and nets, part order shuffled) for the footprints in the layout excerpt that follows; sources: Cadence DE-HDL packaged netlist, KiCad conversion of 12092022_DA0F0TMDCD0_F0T_Management_Board_D_brd_V3_OCP.brd

C197  Q_CAP  0.1UF 25V 10% X7R  pkg 0402  page 49 : A = HDD_LED_P5V_AUX ; B = GND
R879  Q_RES  200 1% CHIP  pkg 0402LF  page 12 : A = SMB_BMC_MM16_R5_SCL ; B = SMB_BMC_MM16_SCL

(kicad_pcb
	(version 20260206)
	(generator "pcbnew")
	(generator_version "10.0")
	(general
		(thickness 1.6)
		(legacy_teardrops no)
	)
	(paper "A4")
	(title_block
		(title "12092022_DA0F0TMDCD0_F0T_Management_Board_D_brd_V3_OCP.brd")
		(comment 1 "Grand Teton / footprints 907-908 of 1440")
	)
	(layers
		(0 "F.Cu" signal "TOP")
		(4 "In1.Cu" signal "GND")
		(6 "In2.Cu" signal "IN1")
		(8 "In3.Cu" signal "GND1")
		(10 "In4.Cu" signal "IN2")
		(12 "In5.Cu" signal "VCC")
		(14 "In6.Cu" signal "VCC1")
		(16 "In7.Cu" signal "IN3")
		(18 "In8.Cu" signal "GND2")
		(20 "In9.Cu" signal "IN4")
		(22 "In10.Cu" signal "GND3")
		(2 "B.Cu" signal "BOTTOM")
		(9 "F.Adhes" user "F.Adhesive")
		(11 "B.Adhes" user "B.Adhesive")
		(13 "F.Paste" user "Package Geometry/Pastemask Top")
		(15 "B.Paste" user "Package Geometry/Pastemask Bottom")
		(5 "F.SilkS" user "Ref Des/Silkscreen Top")
		(7 "B.SilkS" user "Ref Des/Silkscreen Bottom")
		(1 "F.Mask" user "Board Geometry/Soldermask Top")
		(3 "B.Mask" user "Board Geometry/Soldermask Bottom")
		(17 "Dwgs.User" user "User.Drawings")
		(19 "Cmts.User" user "User.Comments")
		(21 "Eco1.User" user "User.Eco1")
		(23 "Eco2.User" user "User.Eco2")
		(25 "Edge.Cuts" user "Board Geometry/Outline")
		(27 "Margin" user)
		(31 "F.CrtYd" user "Package Geometry/Place Bound Top")
		(29 "B.CrtYd" user "Package Geometry/Place Bound Bottom")
		(35 "F.Fab" user "Ref Des/Assembly Top")
		(33 "B.Fab" user "Ref Des/Assembly Bottom")
	)
	(footprint ""
		(layer "B.Cu")
		(at 22.987 -18.669 -90)
		(property "Reference" "C197"
			(at 0 0 90)
			(layer "B.SilkS")
			(hide yes)
			(effects
				(font
					(size 1.27 1.27)
				)
				(justify mirror)
			)
		)
		(property "Value" ""
			(at 0 0 90)
			(layer "B.Fab")
			(effects
				(font
					(size 1.27 1.27)
				)
				(justify mirror)
			)
		)
		(duplicate_pad_numbers_are_jumpers no)
		(fp_line
			(start -0.7874 0.4064)
			(end 0.7874 0.4064)
			(stroke
				(width 0.1524)
				(type default)
			)
			(layer "B.SilkS")
		)
		(fp_line
			(start 0.7874 0.4064)
			(end 0.7874 -0.4064)
			(stroke
				(width 0.1524)
				(type default)
			)
			(layer "B.SilkS")
		)
		(fp_line
			(start -0.7874 -0.4064)
			(end -0.7874 0.4064)
			(stroke
				(width 0.1524)
				(type default)
			)
			(layer "B.SilkS")
		)
		(fp_line
			(start 0.7874 -0.4064)
			(end -0.7874 -0.4064)
			(stroke
				(width 0.1524)
				(type default)
			)
			(layer "B.SilkS")
		)
		(fp_line
			(start -0.67945 0.3048)
			(end -0.120396 0.3048)
			(stroke
				(width 0.1)
				(type default)
			)
			(layer "B.Fab")
		)
		(fp_line
			(start -0.120396 0.3048)
			(end -0.120396 0.2794)
			(stroke
				(width 0.1)
				(type default)
			)
			(layer "B.Fab")
		)
		(fp_line
			(start 0.12065 0.3048)
			(end 0.67945 0.3048)
			(stroke
				(width 0.1)
				(type default)
			)
			(layer "B.Fab")
		)
		(fp_line
			(start 0.67945 0.3048)
			(end 0.67945 -0.305054)
			(stroke
				(width 0.1)
				(type default)
			)
			(layer "B.Fab")
		)
		(fp_line
			(start -0.120396 0.2794)
			(end 0.12065 0.2794)
			(stroke
				(width 0.1)
				(type default)
			)
			(layer "B.Fab")
		)
		(fp_line
			(start 0.12065 0.2794)
			(end 0.12065 0.3048)
			(stroke
				(width 0.1)
				(type default)
			)
			(layer "B.Fab")
		)
		(fp_line
			(start -0.12065 -0.2794)
			(end -0.12065 -0.3048)
			(stroke
				(width 0.1)
				(type default)
			)
			(layer "B.Fab")
		)
		(fp_line
			(start 0.12065 -0.2794)
			(end -0.12065 -0.2794)
			(stroke
				(width 0.1)
				(type default)
			)
			(layer "B.Fab")
		)
		(fp_line
			(start -0.67945 -0.3048)
			(end -0.67945 0.3048)
			(stroke
				(width 0.1)
				(type default)
			)
			(layer "B.Fab")
		)
		(fp_line
			(start -0.12065 -0.3048)
			(end -0.67945 -0.3048)
			(stroke
				(width 0.1)
				(type default)
			)
			(layer "B.Fab")
		)
		(fp_line
			(start 0.12065 -0.305054)
			(end 0.12065 -0.2794)
			(stroke
				(width 0.1)
				(type default)
			)
			(layer "B.Fab")
		)
		(fp_line
			(start 0.67945 -0.305054)
			(end 0.12065 -0.305054)
			(stroke
				(width 0.1)
				(type default)
			)
			(layer "B.Fab")
		)
		(pad "1" smd circle
			(at 0.40005 0 90)
			(size 0 0)
			(layers "B.Cu" "B.Mask" "B.Paste")
			(net "HDD_LED_P5V_AUX")
		)
		(pad "2" smd circle
			(at -0.40005 0 90)
			(size 0 0)
			(layers "B.Cu" "B.Mask" "B.Paste")
			(net "GND")
		)
	)
	(footprint ""
		(layer "B.Cu")
		(at 50.8 -28.829 -90)
		(property "Reference" "R879"
			(at 0 0 90)
			(layer "B.SilkS")
			(hide yes)
			(effects
				(font
					(size 1.27 1.27)
				)
				(justify mirror)
			)
		)
		(property "Value" ""
			(at 0 0 90)
			(layer "B.Fab")
			(effects
				(font
					(size 1.27 1.27)
				)
				(justify mirror)
			)
		)
		(duplicate_pad_numbers_are_jumpers no)
		(fp_line
			(start -0.7874 0.4064)
			(end 0.7874 0.4064)
			(stroke
				(width 0.1524)
				(type default)
			)
			(layer "B.SilkS")
		)
		(fp_line
			(start 0.7874 0.4064)
			(end 0.7874 -0.4064)
			(stroke
				(width 0.1524)
				(type default)
			)
			(layer "B.SilkS")
		)
		(fp_line
			(start -0.7874 -0.4064)
			(end -0.7874 0.4064)
			(stroke
				(width 0.1524)
				(type default)
			)
			(layer "B.SilkS")
		)
		(fp_line
			(start 0.7874 -0.4064)
			(end -0.7874 -0.4064)
			(stroke
				(width 0.1524)
				(type default)
			)
			(layer "B.SilkS")
		)
		(fp_line
			(start -0.67945 0.3048)
			(end -0.120396 0.3048)
			(stroke
				(width 0.1)
				(type default)
			)
			(layer "B.Fab")
		)
		(fp_line
			(start -0.120396 0.3048)
			(end -0.120396 0.2794)
			(stroke
				(width 0.1)
				(type default)
			)
			(layer "B.Fab")
		)
		(fp_line
			(start 0.12065 0.3048)
			(end 0.67945 0.3048)
			(stroke
				(width 0.1)
				(type default)
			)
			(layer "B.Fab")
		)
		(fp_line
			(start 0.67945 0.3048)
			(end 0.67945 -0.305054)
			(stroke
				(width 0.1)
				(type default)
			)
			(layer "B.Fab")
		)
		(fp_line
			(start -0.120396 0.2794)
			(end 0.12065 0.2794)
			(stroke
				(width 0.1)
				(type default)
			)
			(layer "B.Fab")
		)
		(fp_line
			(start 0.12065 0.2794)
			(end 0.12065 0.3048)
			(stroke
				(width 0.1)
				(type default)
			)
			(layer "B.Fab")
		)
		(fp_line
			(start -0.12065 -0.2794)
			(end -0.12065 -0.3048)
			(stroke
				(width 0.1)
				(type default)
			)
			(layer "B.Fab")
		)
		(fp_line
			(start 0.12065 -0.2794)
			(end -0.12065 -0.2794)
			(stroke
				(width 0.1)
				(type default)
			)
			(layer "B.Fab")
		)
		(fp_line
			(start -0.67945 -0.3048)
			(end -0.67945 0.3048)
			(stroke
				(width 0.1)
				(type default)
			)
			(layer "B.Fab")
		)
		(fp_line
			(start -0.12065 -0.3048)
			(end -0.67945 -0.3048)
			(stroke
				(width 0.1)
				(type default)
			)
			(layer "B.Fab")
		)
		(fp_line
			(start 0.12065 -0.305054)
			(end 0.12065 -0.2794)
			(stroke
				(width 0.1)
				(type default)
			)
			(layer "B.Fab")
		)
		(fp_line
			(start 0.67945 -0.305054)
			(end 0.12065 -0.305054)
			(stroke
				(width 0.1)
				(type default)
			)
			(layer "B.Fab")
		)
		(pad "1" smd circle
			(at 0.40005 0 90)
			(size 0 0)
			(layers "B.Cu" "B.Mask" "B.Paste")
			(net "SMB_BMC_MM16_R5_SCL")
		)
		(pad "2" smd circle
			(at -0.40005 0 90)
			(size 0 0)
			(layers "B.Cu" "B.Mask" "B.Paste")
			(net "SMB_BMC_MM16_SCL")
		)
	)
)
